(kicad_pcb
	(version 20260206)
	(generator "pcbnew")
	(generator_version "10.0")
	(general
		(thickness 1.6)
		(legacy_teardrops no)
	)
	(paper "A4")
	(title_block
		(title "baseboard — 13948-1b.1110WZS1818.brd")
		(comment 1 "Honey Badger (Wiwynn) / footprints 1213-1218 of 2523")
	)
	(layers
		(0 "F.Cu" signal "TOP")
		(4 "In1.Cu" signal "L2GND")
		(6 "In2.Cu" signal "L3")
		(8 "In3.Cu" signal "L4VCC")
		(10 "In4.Cu" signal "L5VCC")
		(12 "In5.Cu" signal "L6")
		(14 "In6.Cu" signal "L7GND")
		(2 "B.Cu" signal "BOTTOM")
		(9 "F.Adhes" user "F.Adhesive")
		(11 "B.Adhes" user "B.Adhesive")
		(13 "F.Paste" user "Package Geometry/Pastemask Top")
		(15 "B.Paste" user "Package Geometry/Pastemask Bottom")
		(5 "F.SilkS" user "Ref Des/Silkscreen Top")
		(7 "B.SilkS" user "Ref Des/Silkscreen Bottom")
		(1 "F.Mask" user "Board Geometry/Soldermask Top")
		(3 "B.Mask" user "Board Geometry/Soldermask Bottom")
		(17 "Dwgs.User" user "User.Drawings")
		(19 "Cmts.User" user "User.Comments")
		(21 "Eco1.User" user "User.Eco1")
		(23 "Eco2.User" user "User.Eco2")
		(25 "Edge.Cuts" user "Board Geometry/Outline")
		(27 "Margin" user)
		(31 "F.CrtYd" user "Package Geometry/Place Bound Top")
		(29 "B.CrtYd" user "Package Geometry/Place Bound Bottom")
		(35 "F.Fab" user "Ref Des/Assembly Top")
		(33 "B.Fab" user "Ref Des/Assembly Bottom")
	)
	(footprint ""
		(layer "F.Cu")
		(at 286.639 -210.693 180)
		(property "Reference" "C170"
			(at 0 0 180)
			(layer "F.SilkS")
			(hide yes)
			(effects
				(font
					(size 1.27 1.27)
				)
			)
		)
		(property "Value" "SC10U6D3V5KX-4GP"
			(at -0.0762 -6.1214 180)
			(unlocked yes)
			(layer "F.Fab")
			(hide yes)
			(effects
				(font
					(size 1.016 1.016)
					(thickness 0.1524)
				)
			)
		)
		(property "Device Type" "C805H58"
			(at -0.0762 -8.1534 180)
			(unlocked yes)
			(layer "F.Fab")
			(hide yes)
			(effects
				(font
					(size 1.016 1.016)
					(thickness 0.1524)
				)
			)
		)
		(duplicate_pad_numbers_are_jumpers no)
		(fp_line
			(start 0.635 0)
			(end -0.635 0)
			(stroke
				(width 0.508)
				(type default)
			)
			(layer "F.SilkS")
		)
		(fp_rect
			(start -0.9652 1.778)
			(end 0.9652 -1.778)
			(stroke
				(width 0)
				(type default)
			)
			(fill no)
			(layer "F.CrtYd")
		)
		(fp_poly
			(pts
				(xy -0.9652 -1.778) (xy 0.9652 -1.778) (xy 0.9652 1.778) (xy -0.9652 1.778)
			)
			(stroke
				(width 0)
				(type default)
			)
			(fill no)
			(layer "F.Fab")
		)
		(pad "1" smd rect
			(at 0 -0.9652 180)
			(size 1.397 1.143)
			(layers "F.Cu" "F.Mask" "F.Paste")
			(net "P1V53_STBY")
		)
		(pad "2" smd rect
			(at 0 0.9652 180)
			(size 1.397 1.143)
			(layers "F.Cu" "F.Mask" "F.Paste")
			(net "GND")
		)
	)
	(footprint ""
		(layer "F.Cu")
		(at 194.818 -118.237 180)
		(property "Reference" "R601"
			(at 0 0 180)
			(layer "F.SilkS")
			(hide yes)
			(effects
				(font
					(size 1.27 1.27)
				)
			)
		)
		(property "Value" "0R2J-2-GP"
			(at 0.064008 -3.993896 180)
			(unlocked yes)
			(layer "F.Fab")
			(hide yes)
			(effects
				(font
					(size 1.016 1.016)
					(thickness 0.1524)
				)
			)
		)
		(property "Device Type" "R402H16"
			(at 0.064008 -5.517896 180)
			(unlocked yes)
			(layer "F.Fab")
			(hide yes)
			(effects
				(font
					(size 1.016 1.016)
					(thickness 0.1524)
				)
			)
		)
		(duplicate_pad_numbers_are_jumpers no)
		(fp_line
			(start 0.508 -0.9398)
			(end -0.508 -0.9398)
			(stroke
				(width 0.1524)
				(type default)
			)
			(layer "F.SilkS")
		)
		(fp_line
			(start -0.508 -0.9398)
			(end -0.508 0.9398)
			(stroke
				(width 0.1524)
				(type default)
			)
			(layer "F.SilkS")
		)
		(fp_rect
			(start -0.508 0.9398)
			(end 0.508 -0.9398)
			(stroke
				(width 0)
				(type default)
			)
			(fill no)
			(layer "F.CrtYd")
		)
		(fp_rect
			(start -0.508 0.9398)
			(end 0.508 -0.9398)
			(stroke
				(width 0)
				(type default)
			)
			(fill no)
			(layer "F.Fab")
		)
		(pad "1" smd custom
			(at 0 -0.4445 180)
			(size 0.1397 0.1397)
			(layers "F.Cu" "F.Mask" "F.Paste")
			(net "P1V8_E_PG")
			(options
				(clearance outline)
				(anchor circle)
			)
			(primitives
				(gr_poly
					(pts
						(arc
							(start -0.1778 -0.2794)
							(mid -0.249642 -0.249642)
							(end -0.2794 -0.1778)
						)
						(arc
							(start -0.2794 0.1778)
							(mid -0.249642 0.249642)
							(end -0.1778 0.2794)
						)
						(arc
							(start 0.1778 0.2794)
							(mid 0.249642 0.249642)
							(end 0.2794 0.1778)
						)
						(arc
							(start 0.2794 -0.1778)
							(mid 0.249642 -0.249642)
							(end 0.1778 -0.2794)
						)
					)
					(width 0)
					(fill yes)
				)
			)
		)
		(pad "2" smd custom
			(at 0 0.4445 180)
			(size 0.1397 0.1397)
			(layers "F.Cu" "F.Mask" "F.Paste")
			(net "P1V8_PG_R_1")
			(options
				(clearance outline)
				(anchor circle)
			)
			(primitives
				(gr_poly
					(pts
						(arc
							(start -0.1778 -0.2794)
							(mid -0.249642 -0.249642)
							(end -0.2794 -0.1778)
						)
						(arc
							(start -0.2794 0.1778)
							(mid -0.249642 0.249642)
							(end -0.1778 0.2794)
						)
						(arc
							(start 0.1778 0.2794)
							(mid 0.249642 0.249642)
							(end 0.2794 0.1778)
						)
						(arc
							(start 0.2794 -0.1778)
							(mid 0.249642 -0.249642)
							(end 0.1778 -0.2794)
						)
					)
					(width 0)
					(fill yes)
				)
			)
		)
	)
	(footprint ""
		(layer "F.Cu")
		(at 131.069842 -84.399882 90)
		(property "Reference" "SC1097"
			(at 0 0 90)
			(layer "F.SilkS")
			(hide yes)
			(effects
				(font
					(size 1.27 1.27)
				)
			)
		)
		(property "Value" "SCD01U10V1KX-GP"
			(at -2.8321 -1.7399 90)
			(unlocked yes)
			(layer "F.Fab")
			(hide yes)
			(effects
				(font
					(size 1.016 1.016)
					(thickness 0.1524)
				)
			)
		)
		(property "Device Type" "C0201H13"
			(at -2.8321 -3.2639 90)
			(unlocked yes)
			(layer "F.Fab")
			(hide yes)
			(effects
				(font
					(size 1.016 1.016)
					(thickness 0.1524)
				)
			)
		)
		(duplicate_pad_numbers_are_jumpers no)
		(fp_rect
			(start -0.2794 0.6477)
			(end 0.2794 -0.6477)
			(stroke
				(width 0)
				(type default)
			)
			(fill no)
			(layer "F.CrtYd")
		)
		(fp_rect
			(start -0.2794 0.6477)
			(end 0.2794 -0.6477)
			(stroke
				(width 0)
				(type default)
			)
			(fill no)
			(layer "F.Fab")
		)
		(pad "1" smd custom
			(at 0 -0.2794 90)
			(size 0.0762 0.0762)
			(layers "F.Cu" "F.Mask" "F.Paste")
			(net "SAS_HDD_TX15_N")
			(options
				(clearance outline)
				(anchor circle)
			)
			(primitives
				(gr_poly
					(pts
						(arc
							(start 0.1524 -0.127)
							(mid 0.137521 -0.162921)
							(end 0.1016 -0.1778)
						)
						(arc
							(start -0.1016 -0.1778)
							(mid -0.137521 -0.162921)
							(end -0.1524 -0.127)
						)
						(arc
							(start -0.1524 0.127)
							(mid -0.137521 0.162921)
							(end -0.1016 0.1778)
						)
						(arc
							(start 0.1016 0.1778)
							(mid 0.137521 0.162921)
							(end 0.1524 0.127)
						)
					)
					(width 0)
					(fill yes)
				)
			)
		)
		(pad "2" smd custom
			(at 0 0.2794 90)
			(size 0.0762 0.0762)
			(layers "F.Cu" "F.Mask" "F.Paste")
			(net "3008_SAS_RX_N3")
			(options
				(clearance outline)
				(anchor circle)
			)
			(primitives
				(gr_poly
					(pts
						(arc
							(start 0.1524 -0.127)
							(mid 0.137521 -0.162921)
							(end 0.1016 -0.1778)
						)
						(arc
							(start -0.1016 -0.1778)
							(mid -0.137521 -0.162921)
							(end -0.1524 -0.127)
						)
						(arc
							(start -0.1524 0.127)
							(mid -0.137521 0.162921)
							(end -0.1016 0.1778)
						)
						(arc
							(start 0.1016 0.1778)
							(mid 0.137521 0.162921)
							(end 0.1524 0.127)
						)
					)
					(width 0)
					(fill yes)
				)
			)
		)
	)
	(footprint ""
		(layer "F.Cu")
		(at 301.498 -102.108 180)
		(property "Reference" "R165"
			(at 0 0 180)
			(layer "F.SilkS")
			(hide yes)
			(effects
				(font
					(size 1.27 1.27)
				)
			)
		)
		(property "Value" "4K7R2F-GP"
			(at 0.064008 -3.993896 180)
			(unlocked yes)
			(layer "F.Fab")
			(hide yes)
			(effects
				(font
					(size 1.016 1.016)
					(thickness 0.1524)
				)
			)
		)
		(property "Device Type" "R402H16"
			(at 0.064008 -5.517896 180)
			(unlocked yes)
			(layer "F.Fab")
			(hide yes)
			(effects
				(font
					(size 1.016 1.016)
					(thickness 0.1524)
				)
			)
		)
		(duplicate_pad_numbers_are_jumpers no)
		(fp_line
			(start 0.508 -0.9398)
			(end -0.508 -0.9398)
			(stroke
				(width 0.1524)
				(type default)
			)
			(layer "F.SilkS")
		)
		(fp_line
			(start -0.508 -0.9398)
			(end -0.508 0.9398)
			(stroke
				(width 0.1524)
				(type default)
			)
			(layer "F.SilkS")
		)
		(fp_rect
			(start -0.508 0.9398)
			(end 0.508 -0.9398)
			(stroke
				(width 0)
				(type default)
			)
			(fill no)
			(layer "F.CrtYd")
		)
		(fp_rect
			(start -0.508 0.9398)
			(end 0.508 -0.9398)
			(stroke
				(width 0)
				(type default)
			)
			(fill no)
			(layer "F.Fab")
		)
		(pad "1" smd custom
			(at 0 -0.4445 180)
			(size 0.1397 0.1397)
			(layers "F.Cu" "F.Mask" "F.Paste")
			(net "TEMP_2_A1")
			(options
				(clearance outline)
				(anchor circle)
			)
			(primitives
				(gr_poly
					(pts
						(arc
							(start -0.1778 -0.2794)
							(mid -0.249642 -0.249642)
							(end -0.2794 -0.1778)
						)
						(arc
							(start -0.2794 0.1778)
							(mid -0.249642 0.249642)
							(end -0.1778 0.2794)
						)
						(arc
							(start 0.1778 0.2794)
							(mid 0.249642 0.249642)
							(end 0.2794 0.1778)
						)
						(arc
							(start 0.2794 -0.1778)
							(mid 0.249642 -0.249642)
							(end 0.1778 -0.2794)
						)
					)
					(width 0)
					(fill yes)
				)
			)
		)
		(pad "2" smd custom
			(at 0 0.4445 180)
			(size 0.1397 0.1397)
			(layers "F.Cu" "F.Mask" "F.Paste")
			(net "GND")
			(options
				(clearance outline)
				(anchor circle)
			)
			(primitives
				(gr_poly
					(pts
						(arc
							(start -0.1778 -0.2794)
							(mid -0.249642 -0.249642)
							(end -0.2794 -0.1778)
						)
						(arc
							(start -0.2794 0.1778)
							(mid -0.249642 0.249642)
							(end -0.1778 0.2794)
						)
						(arc
							(start 0.1778 0.2794)
							(mid 0.249642 0.249642)
							(end 0.2794 0.1778)
						)
						(arc
							(start 0.2794 -0.1778)
							(mid 0.249642 -0.249642)
							(end 0.1778 -0.2794)
						)
					)
					(width 0)
					(fill yes)
				)
			)
		)
	)
	(footprint ""
		(layer "F.Cu")
		(at 51.689 -225.298 180)
		(property "Reference" "C7276"
			(at 0 0 180)
			(layer "F.SilkS")
			(hide yes)
			(effects
				(font
					(size 1.27 1.27)
				)
			)
		)
		(property "Value" "SC1U16V3KX-5GP"
			(at 0 -2.8194 180)
			(unlocked yes)
			(layer "F.Fab")
			(hide yes)
			(effects
				(font
					(size 1.016 1.016)
					(thickness 0.1524)
				)
			)
		)
		(property "Device Type" "C603H36"
			(at 0 -4.3434 180)
			(unlocked yes)
			(layer "F.Fab")
			(hide yes)
			(effects
				(font
					(size 1.016 1.016)
					(thickness 0.1524)
				)
			)
		)
		(duplicate_pad_numbers_are_jumpers no)
		(fp_line
			(start 0.508 0)
			(end -0.508 0)
			(stroke
				(width 0.2032)
				(type default)
			)
			(layer "F.SilkS")
		)
		(fp_rect
			(start -0.5842 1.3335)
			(end 0.5842 -1.3335)
			(stroke
				(width 0)
				(type default)
			)
			(fill no)
			(layer "F.CrtYd")
		)
		(fp_rect
			(start -0.5842 1.3335)
			(end 0.5842 -1.3335)
			(stroke
				(width 0)
				(type default)
			)
			(fill no)
			(layer "F.Fab")
		)
		(pad "1" smd custom
			(at 0 -0.762 180)
			(size 0.2159 0.2159)
			(layers "F.Cu" "F.Mask" "F.Paste")
			(net "MB0_CM_UV_R")
			(options
				(clearance outline)
				(anchor circle)
			)
			(primitives
				(gr_poly
					(pts
						(arc
							(start -0.3302 -0.4318)
							(mid -0.402042 -0.402042)
							(end -0.4318 -0.3302)
						)
						(arc
							(start -0.4318 0.3302)
							(mid -0.402042 0.402042)
							(end -0.3302 0.4318)
						)
						(arc
							(start 0.3302 0.4318)
							(mid 0.402042 0.402042)
							(end 0.4318 0.3302)
						)
						(arc
							(start 0.4318 -0.3302)
							(mid 0.402042 -0.402042)
							(end 0.3302 -0.4318)
						)
					)
					(width 0)
					(fill yes)
				)
			)
		)
		(pad "2" smd custom
			(at 0 0.762 180)
			(size 0.2159 0.2159)
			(layers "F.Cu" "F.Mask" "F.Paste")
			(net "AGND_CURRENT_MON")
			(options
				(clearance outline)
				(anchor circle)
			)
			(primitives
				(gr_poly
					(pts
						(arc
							(start -0.3302 -0.4318)
							(mid -0.402042 -0.402042)
							(end -0.4318 -0.3302)
						)
						(arc
							(start -0.4318 0.3302)
							(mid -0.402042 0.402042)
							(end -0.3302 0.4318)
						)
						(arc
							(start 0.3302 0.4318)
							(mid 0.402042 0.402042)
							(end 0.4318 0.3302)
						)
						(arc
							(start 0.4318 -0.3302)
							(mid 0.402042 -0.402042)
							(end 0.3302 -0.4318)
						)
					)
					(width 0)
					(fill yes)
				)
			)
		)
	)
	(footprint ""
		(layer "F.Cu")
		(at 171.619164 -24.014176 -90)
		(property "Reference" "R406"
			(at 0 0 270)
			(layer "F.SilkS")
			(hide yes)
			(effects
				(font
					(size 1.27 1.27)
				)
			)
		)
		(property "Value" "220R2J-L2-GP"
			(at 0.064008 -3.993896 270)
			(unlocked yes)
			(layer "F.Fab")
			(hide yes)
			(effects
				(font
					(size 1.016 1.016)
					(thickness 0.1524)
				)
			)
		)
		(property "Device Type" "R402H16"
			(at 0.064008 -5.517896 270)
			(unlocked yes)
			(layer "F.Fab")
			(hide yes)
			(effects
				(font
					(size 1.016 1.016)
					(thickness 0.1524)
				)
			)
		)
		(duplicate_pad_numbers_are_jumpers no)
		(fp_line
			(start -0.508 -0.9398)
			(end -0.508 0.9398)
			(stroke
				(width 0.1524)
				(type default)
			)
			(layer "F.SilkS")
		)
		(fp_line
			(start 0.508 -0.9398)
			(end -0.508 -0.9398)
			(stroke
				(width 0.1524)
				(type default)
			)
			(layer "F.SilkS")
		)
		(fp_rect
			(start -0.508 0.9398)
			(end 0.508 -0.9398)
			(stroke
				(width 0)
				(type default)
			)
			(fill no)
			(layer "F.CrtYd")
		)
		(fp_rect
			(start -0.508 0.9398)
			(end 0.508 -0.9398)
			(stroke
				(width 0)
				(type default)
			)
			(fill no)
			(layer "F.Fab")
		)
		(pad "1" smd custom
			(at 0 -0.4445 270)
			(size 0.1397 0.1397)
			(layers "F.Cu" "F.Mask" "F.Paste")
			(net "MOD_IMC_FAB_D_COP")
			(options
				(clearance outline)
				(anchor circle)
			)
			(primitives
				(gr_poly
					(pts
						(arc
							(start -0.1778 -0.2794)
							(mid -0.249642 -0.249642)
							(end -0.2794 -0.1778)
						)
						(arc
							(start -0.2794 0.1778)
							(mid -0.249642 0.249642)
							(end -0.1778 0.2794)
						)
						(arc
							(start 0.1778 0.2794)
							(mid 0.249642 0.249642)
							(end 0.2794 0.1778)
						)
						(arc
							(start 0.2794 -0.1778)
							(mid 0.249642 -0.249642)
							(end 0.1778 -0.2794)
						)
					)
					(width 0)
					(fill yes)
				)
			)
		)
		(pad "2" smd custom
			(at 0 0.4445 270)
			(size 0.1397 0.1397)
			(layers "F.Cu" "F.Mask" "F.Paste")
			(net "GND")
			(options
				(clearance outline)
				(anchor circle)
			)
			(primitives
				(gr_poly
					(pts
						(arc
							(start -0.1778 -0.2794)
							(mid -0.249642 -0.249642)
							(end -0.2794 -0.1778)
						)
						(arc
							(start -0.2794 0.1778)
							(mid -0.249642 0.249642)
							(end -0.1778 0.2794)
						)
						(arc
							(start 0.1778 0.2794)
							(mid 0.249642 0.249642)
							(end 0.2794 0.1778)
						)
						(arc
							(start 0.2794 -0.1778)
							(mid 0.249642 -0.249642)
							(end 0.1778 -0.2794)
						)
					)
					(width 0)
					(fill yes)
				)
			)
		)
	)
)
